(kicad_pcb
	(version 20241229)
	(generator "pcbnew")
	(generator_version "9.0")
	(general
		(thickness 1.6)
		(legacy_teardrops no)
	)
	(paper "A4")
	(title_block
		(title "OCuLink to PCIe adapter")
		(date "2025-06-18")
		(rev "1.0.0")
		(company "Antmicro Ltd")
		(comment 1 "www.antmicro.com")
		(comment 9 "footprints 57-62 of 159")
	)
	(layers
		(0 "F.Cu" signal)
		(4 "In1.Cu" signal)
		(6 "In2.Cu" signal)
		(2 "B.Cu" signal)
		(9 "F.Adhes" user "F.Adhesive")
		(11 "B.Adhes" user "B.Adhesive")
		(13 "F.Paste" user)
		(15 "B.Paste" user)
		(5 "F.SilkS" user "F.Silkscreen")
		(7 "B.SilkS" user "B.Silkscreen")
		(1 "F.Mask" user)
		(3 "B.Mask" user)
		(17 "Dwgs.User" user "User.Drawings")
		(19 "Cmts.User" user "User.Comments")
		(21 "Eco1.User" user "User.Eco1")
		(23 "Eco2.User" user "User.Eco2")
		(25 "Edge.Cuts" user)
		(27 "Margin" user)
		(31 "F.CrtYd" user "F.Courtyard")
		(29 "B.CrtYd" user "B.Courtyard")
		(35 "F.Fab" user)
		(33 "B.Fab" user)
	)
	(footprint "antmicro-footprints:R_0402_1005Metric"
		(layer "F.Cu")
		(at 119.55 48.2 90)
		(descr "Resistor SMD 0402")
		(tags "resistor SMD 0402")
		(property "Reference" "R43"
			(at -3.2 0.45 90)
			(layer "F.SilkS")
			(effects
				(font
					(size 0.7 0.7)
					(thickness 0.15)
				)
				(justify left bottom)
			)
		)
		(property "Value" "R_0R_0402"
			(at -1.011843 1.772046 90)
			(layer "F.Fab")
			(effects
				(font
					(size 0.7 0.7)
					(thickness 0.15)
				)
				(justify left bottom)
			)
		)
		(property "Datasheet" "https://industrial.panasonic.com/cdbs/www-data/pdf/RDA0000/AOA0000C301.pdf"
			(at 0 0 90)
			(layer "F.Fab")
			(hide yes)
			(effects
				(font
					(size 1.27 1.27)
					(thickness 0.15)
				)
			)
		)
		(property "Description" "SMD Chip Resistor, Jumper, 0 ohm, 100 mW, 0402 [1005 Metric], Thick Film, General Purpose"
			(at 0 0 90)
			(layer "F.Fab")
			(hide yes)
			(effects
				(font
					(size 1.27 1.27)
					(thickness 0.15)
				)
			)
		)
		(property "MPN" "ERJ2GE0R00X"
			(at 0 0 90)
			(unlocked yes)
			(layer "F.Fab")
			(hide yes)
			(effects
				(font
					(size 1 1)
					(thickness 0.15)
				)
			)
		)
		(property "Manufacturer" "Panasonic"
			(at 0 0 90)
			(unlocked yes)
			(layer "F.Fab")
			(hide yes)
			(effects
				(font
					(size 1 1)
					(thickness 0.15)
				)
			)
		)
		(property "License" "Apache-2.0"
			(at 0 0 90)
			(unlocked yes)
			(layer "F.Fab")
			(hide yes)
			(effects
				(font
					(size 1 1)
					(thickness 0.15)
				)
			)
		)
		(property "Author" "Antmicro"
			(at 0 0 90)
			(unlocked yes)
			(layer "F.Fab")
			(hide yes)
			(effects
				(font
					(size 1 1)
					(thickness 0.15)
				)
			)
		)
		(property "Val" "0R"
			(at 0 0 90)
			(unlocked yes)
			(layer "F.Fab")
			(hide yes)
			(effects
				(font
					(size 1 1)
					(thickness 0.15)
				)
			)
		)
		(property "Tolerance" ""
			(at 0 0 90)
			(unlocked yes)
			(layer "F.Fab")
			(hide yes)
			(effects
				(font
					(size 1 1)
					(thickness 0.15)
				)
			)
		)
		(property "Current" "1A"
			(at 0 0 90)
			(unlocked yes)
			(layer "F.Fab")
			(hide yes)
			(effects
				(font
					(size 1 1)
					(thickness 0.15)
				)
			)
		)
		(sheetname "/PCIe-clock-generator/")
		(sheetfile "pcie-clock-generator.kicad_sch")
		(attr smd exclude_from_bom dnp)
		(fp_poly
			(pts
				(xy -0.925 -0.47) (xy 0.925 -0.47) (xy 0.925 0.47) (xy -0.925 0.47)
			)
			(stroke
				(width 0.05)
				(type default)
			)
			(fill no)
			(layer "F.CrtYd")
		)
		(fp_poly
			(pts
				(xy -0.5 -0.25) (xy 0.5 -0.25) (xy 0.5 0.25) (xy -0.5 0.25)
			)
			(stroke
				(width 0.15)
				(type solid)
			)
			(fill no)
			(layer "F.Fab")
		)
		(fp_text user "${REFERENCE}"
			(at -0.95 3.168 90)
			(layer "F.Fab")
			(effects
				(font
					(size 0.7 0.7)
					(thickness 0.15)
				)
				(justify left bottom)
			)
		)
		(fp_text user "License: Apache-2.0"
			(at -0.949999 5.169 90)
			(layer "F.Fab")
			(effects
				(font
					(size 0.7 0.7)
					(thickness 0.15)
				)
				(justify left bottom)
			)
		)
		(fp_text user "Author: Antmicro"
			(at -0.95 4.169 90)
			(layer "F.Fab")
			(effects
				(font
					(size 0.7 0.7)
					(thickness 0.15)
				)
				(justify left bottom)
			)
		)
		(pad "1" smd roundrect
			(at -0.48 0 90)
			(size 0.59 0.64)
			(layers "F.Cu" "F.Mask" "F.Paste")
			(roundrect_rratio 0.25)
			(net 178 "/PCIe-clock-generator/PCIe_{REF1}_R.CK+")
			(pintype "passive")
		)
		(pad "2" smd roundrect
			(at 0.48 0 90)
			(size 0.59 0.64)
			(layers "F.Cu" "F.Mask" "F.Paste")
			(roundrect_rratio 0.25)
			(net 96 "/OCuLink/PCIe_{REF0}.CK+")
			(pintype "passive")
		)
	)
	(footprint "antmicro-footprints:C_0805_2012Metric"
		(layer "F.Cu")
		(at 103.8 119.4 90)
		(descr "Capacitor SMD 0805")
		(tags "capacitor SMD 0805")
		(property "Reference" "C6"
			(at 0.2 -1 90)
			(layer "F.SilkS")
			(effects
				(font
					(size 0.7 0.7)
					(thickness 0.15)
				)
				(justify left bottom)
			)
		)
		(property "Value" "C_10u_0805_35V"
			(at -2.055717 1.963153 90)
			(layer "F.Fab")
			(effects
				(font
					(size 0.7 0.7)
					(thickness 0.15)
				)
				(justify left bottom)
			)
		)
		(property "Datasheet" "https://www.murata.com/products/productdetail?partno=GRM21BR6YA106KE43%23"
			(at 0 0 90)
			(layer "F.Fab")
			(hide yes)
			(effects
				(font
					(size 1.27 1.27)
					(thickness 0.15)
				)
			)
		)
		(property "Description" "SMD Multilayer Ceramic Capacitor, 10 µF, 35 V, 0805 [2012 Metric], ± 10%, X5R, GRM Series"
			(at 0 0 90)
			(layer "F.Fab")
			(hide yes)
			(effects
				(font
					(size 1.27 1.27)
					(thickness 0.15)
				)
			)
		)
		(property "MPN" "GRM21BR6YA106KE43L"
			(at 0 0 90)
			(unlocked yes)
			(layer "F.Fab")
			(hide yes)
			(effects
				(font
					(size 1 1)
					(thickness 0.15)
				)
			)
		)
		(property "Manufacturer" "Murata"
			(at 0 0 90)
			(unlocked yes)
			(layer "F.Fab")
			(hide yes)
			(effects
				(font
					(size 1 1)
					(thickness 0.15)
				)
			)
		)
		(property "License" "Apache-2.0"
			(at 0 0 90)
			(unlocked yes)
			(layer "F.Fab")
			(hide yes)
			(effects
				(font
					(size 1 1)
					(thickness 0.15)
				)
			)
		)
		(property "Author" "Antmicro"
			(at 0 0 90)
			(unlocked yes)
			(layer "F.Fab")
			(hide yes)
			(effects
				(font
					(size 1 1)
					(thickness 0.15)
				)
			)
		)
		(property "Val" "10u"
			(at 0 0 90)
			(unlocked yes)
			(layer "F.Fab")
			(hide yes)
			(effects
				(font
					(size 1 1)
					(thickness 0.15)
				)
			)
		)
		(property "Voltage" "35V"
			(at 0 0 90)
			(unlocked yes)
			(layer "F.Fab")
			(hide yes)
			(effects
				(font
					(size 1 1)
					(thickness 0.15)
				)
			)
		)
		(property "Dielectric" ""
			(at 0 0 90)
			(unlocked yes)
			(layer "F.Fab")
			(hide yes)
			(effects
				(font
					(size 1 1)
					(thickness 0.15)
				)
			)
		)
		(property "Public" "False"
			(at 0 0 90)
			(unlocked yes)
			(layer "F.Fab")
			(hide yes)
			(effects
				(font
					(size 1 1)
					(thickness 0.15)
				)
			)
		)
		(sheetname "/PCIe-connector/")
		(sheetfile "pcie-connector.kicad_sch")
		(attr smd)
		(fp_line
			(start -0.3 -0.7)
			(end 0.3 -0.7)
			(stroke
				(width 0.15)
				(type solid)
			)
			(layer "F.SilkS")
		)
		(fp_line
			(start -0.3 0.7)
			(end 0.3 0.7)
			(stroke
				(width 0.15)
				(type solid)
			)
			(layer "F.SilkS")
		)
		(fp_rect
			(start 1.95 -0.9)
			(end -1.95 0.9)
			(stroke
				(width 0.05)
				(type default)
			)
			(fill no)
			(layer "F.CrtYd")
		)
		(fp_rect
			(start -0.95 -0.675)
			(end 0.95 0.675)
			(stroke
				(width 0.15)
				(type solid)
			)
			(fill no)
			(layer "F.Fab")
		)
		(fp_text user "License: Apache-2.0"
			(at -1.9 4.947 90)
			(layer "F.Fab")
			(effects
				(font
					(size 0.7 0.7)
					(thickness 0.15)
				)
				(justify left bottom)
			)
		)
		(fp_text user "${REFERENCE}"
			(at 0 0 90)
			(layer "F.Fab")
			(effects
				(font
					(size 0.7 0.7)
					(thickness 0.15)
				)
				(justify left bottom)
			)
		)
		(fp_text user "Author: Antmicro"
			(at -1.9 5.947 90)
			(layer "F.Fab")
			(effects
				(font
					(size 0.7 0.7)
					(thickness 0.15)
				)
				(justify left bottom)
			)
		)
		(pad "1" smd roundrect
			(at -1.1 0 90)
			(size 1.2 1.3)
			(layers "F.Cu" "F.Mask" "F.Paste")
			(roundrect_rratio 0.25)
			(net 87 "+12V")
			(pintype "passive")
		)
		(pad "2" smd roundrect
			(at 1.1 0 90)
			(size 1.2 1.3)
			(layers "F.Cu" "F.Mask" "F.Paste")
			(roundrect_rratio 0.25)
			(net 66 "GND")
			(pintype "passive")
		)
	)
	(footprint "antmicro-footprints:R_0402_1005Metric"
		(layer "F.Cu")
		(at 128.332998 152.076999 -90)
		(descr "Resistor SMD 0402")
		(tags "resistor SMD 0402")
		(property "Reference" "R7"
			(at 0.923001 0.332998 270)
			(layer "F.SilkS")
			(effects
				(font
					(size 0.7 0.7)
					(thickness 0.15)
				)
				(justify right top)
			)
		)
		(property "Value" "R_100k_0402"
			(at -1.011843 1.772046 90)
			(layer "F.Fab")
			(effects
				(font
					(size 0.7 0.7)
					(thickness 0.15)
				)
				(justify right top)
			)
		)
		(property "Datasheet" "https://www.bourns.com/docs/product-datasheets/cr.pdf"
			(at 0 0 90)
			(layer "F.Fab")
			(hide yes)
			(effects
				(font
					(size 1.27 1.27)
					(thickness 0.15)
				)
			)
		)
		(property "Description" "SMD Chip Resistor, 100 kohm, ± 1%, 62.5 mW, 0402 [1005 Metric], Thick Film, General Purpose"
			(at 0 0 90)
			(layer "F.Fab")
			(hide yes)
			(effects
				(font
					(size 1.27 1.27)
					(thickness 0.15)
				)
			)
		)
		(property "MPN" "CR0402-FX-1003GLF"
			(at 0 0 270)
			(unlocked yes)
			(layer "F.Fab")
			(hide yes)
			(effects
				(font
					(size 1 1)
					(thickness 0.15)
				)
			)
		)
		(property "Manufacturer" "Bourns"
			(at 0 0 270)
			(unlocked yes)
			(layer "F.Fab")
			(hide yes)
			(effects
				(font
					(size 1 1)
					(thickness 0.15)
				)
			)
		)
		(property "License" "Apache-2.0"
			(at 0 0 270)
			(unlocked yes)
			(layer "F.Fab")
			(hide yes)
			(effects
				(font
					(size 1 1)
					(thickness 0.15)
				)
			)
		)
		(property "Author" "Antmicro"
			(at 0 0 270)
			(unlocked yes)
			(layer "F.Fab")
			(hide yes)
			(effects
				(font
					(size 1 1)
					(thickness 0.15)
				)
			)
		)
		(property "Val" "100k"
			(at 0 0 270)
			(unlocked yes)
			(layer "F.Fab")
			(hide yes)
			(effects
				(font
					(size 1 1)
					(thickness 0.15)
				)
			)
		)
		(property "Tolerance" "1%"
			(at 0 0 270)
			(unlocked yes)
			(layer "F.Fab")
			(hide yes)
			(effects
				(font
					(size 1 1)
					(thickness 0.15)
				)
			)
		)
		(sheetname "/Power/")
		(sheetfile "power.kicad_sch")
		(attr smd)
		(fp_rect
			(start -0.925 -0.47)
			(end 0.925 0.47)
			(stroke
				(width 0.05)
				(type default)
			)
			(fill no)
			(layer "F.CrtYd")
		)
		(fp_rect
			(start -0.5 -0.25)
			(end 0.5 0.25)
			(stroke
				(width 0.15)
				(type solid)
			)
			(fill no)
			(layer "F.Fab")
		)
		(fp_text user "${REFERENCE}"
			(at 0 0 90)
			(layer "F.Fab")
			(effects
				(font
					(size 0.7 0.7)
					(thickness 0.15)
				)
				(justify right top)
			)
		)
		(fp_text user "Author: Antmicro"
			(at -0.95 4.169 90)
			(layer "F.Fab")
			(effects
				(font
					(size 0.7 0.7)
					(thickness 0.15)
				)
				(justify right top)
			)
		)
		(fp_text user "License: Apache-2.0"
			(at -0.949999 5.169 90)
			(layer "F.Fab")
			(effects
				(font
					(size 0.7 0.7)
					(thickness 0.15)
				)
				(justify right top)
			)
		)
		(pad "1" smd roundrect
			(at -0.48 0 270)
			(size 0.59 0.64)
			(layers "F.Cu" "F.Mask" "F.Paste")
			(roundrect_rratio 0.25)
			(net 66 "GND")
			(pintype "passive")
		)
		(pad "2" smd roundrect
			(at 0.48 0 270)
			(size 0.59 0.64)
			(layers "F.Cu" "F.Mask" "F.Paste")
			(roundrect_rratio 0.25)
			(net 172 "/Power/~{PERST}")
			(pintype "passive")
		)
	)
	(footprint "antmicro-footprints:MP_Pad6mm_Drill3.2mm"
		(layer "F.Cu")
		(at 147.5 47 -90)
		(property "Reference" "MP2"
			(at 0 0 90)
			(layer "F.SilkS")
			(hide yes)
			(effects
				(font
					(size 0.7 0.7)
					(thickness 0.15)
				)
				(justify right top)
			)
		)
		(property "Value" "MP_Pad6mm_Drill3.2mm"
			(at 0 3.899999 90)
			(layer "F.Fab")
			(effects
				(font
					(size 0.7 0.7)
					(thickness 0.15)
				)
				(justify right top)
			)
		)
		(property "Description" "Mechanical part"
			(at 0 0 90)
			(layer "F.Fab")
			(hide yes)
			(effects
				(font
					(size 1.27 1.27)
					(thickness 0.15)
				)
			)
		)
		(property "Author" "Antmicro"
			(at 0 0 270)
			(unlocked yes)
			(layer "F.Fab")
			(hide yes)
			(effects
				(font
					(size 1 1)
					(thickness 0.15)
				)
			)
		)
		(property "License" "Apache-2.0"
			(at 0 0 270)
			(unlocked yes)
			(layer "F.Fab")
			(hide yes)
			(effects
				(font
					(size 1 1)
					(thickness 0.15)
				)
			)
		)
		(sheetname "/")
		(sheetfile "oculink-to-pcie-adapter.kicad_sch")
		(attr exclude_from_pos_files exclude_from_bom)
		(fp_circle
			(center 0 0)
			(end 3.25 0)
			(stroke
				(width 0.05)
				(type default)
			)
			(fill no)
			(layer "F.CrtYd")
		)
		(fp_text user "Author: Antmicro"
			(at -0.178001 7.225 90)
			(layer "F.Fab")
			(effects
				(font
					(size 0.7 0.7)
					(thickness 0.15)
				)
				(justify right top)
			)
		)
		(fp_text user "${REFERENCE}"
			(at 0 0 90)
			(layer "F.Fab")
			(effects
				(font
					(size 0.7 0.7)
					(thickness 0.15)
				)
				(justify right top)
			)
		)
		(fp_text user "License: Apache-2.0"
			(at -0.178 8.425001 90)
			(layer "F.Fab")
			(effects
				(font
					(size 0.7 0.7)
					(thickness 0.15)
				)
				(justify right top)
			)
		)
		(pad "1" thru_hole circle
			(at 0 0 270)
			(size 6 6)
			(drill 3.2)
			(layers "*.Cu" "*.Mask")
			(remove_unused_layers no)
			(net 66 "GND")
			(pintype "passive")
		)
	)
	(footprint "antmicro-footprints:TP_Pad0.75mm_Drill0.2mm"
		(layer "F.Cu")
		(at 155.75 150 -90)
		(property "Reference" "TP2"
			(at 0.5 -0.6 0)
			(layer "F.SilkS")
			(effects
				(font
					(size 0.7 0.7)
					(thickness 0.15)
				)
				(justify left bottom)
			)
		)
		(property "Value" "TP_Pad0.75mm_Drill0.2mm"
			(at 0 1.2 270)
			(layer "F.Fab")
			(effects
				(font
					(size 0.7 0.7)
					(thickness 0.15)
				)
				(justify left bottom)
			)
		)
		(property "Description" "SMT test point"
			(at 0 0 270)
			(layer "F.Fab")
			(hide yes)
			(effects
				(font
					(size 1.27 1.27)
					(thickness 0.15)
				)
			)
		)
		(property "MPN" ""
			(at 0 0 270)
			(unlocked yes)
			(layer "F.Fab")
			(hide yes)
			(effects
				(font
					(size 1 1)
					(thickness 0.15)
				)
			)
		)
		(property "Manufacturer" ""
			(at 0 0 270)
			(unlocked yes)
			(layer "F.Fab")
			(hide yes)
			(effects
				(font
					(size 1 1)
					(thickness 0.15)
				)
			)
		)
		(property "Author" "Antmicro"
			(at 0 0 270)
			(unlocked yes)
			(layer "F.Fab")
			(hide yes)
			(effects
				(font
					(size 1 1)
					(thickness 0.15)
				)
			)
		)
		(property "License" "Apache-2.0"
			(at 0 0 270)
			(unlocked yes)
			(layer "F.Fab")
			(hide yes)
			(effects
				(font
					(size 1 1)
					(thickness 0.15)
				)
			)
		)
		(sheetname "/Power/")
		(sheetfile "power.kicad_sch")
		(attr exclude_from_pos_files exclude_from_bom)
		(fp_circle
			(center 0 0)
			(end 0.475 0)
			(stroke
				(width 0.05)
				(type default)
			)
			(fill no)
			(layer "F.CrtYd")
		)
		(fp_text user "License: Apache-2.0"
			(at -0.4 5.101 270)
			(layer "F.Fab")
			(effects
				(font
					(size 0.7 0.7)
					(thickness 0.15)
				)
				(justify left bottom)
			)
		)
		(fp_text user "Author: Antmicro"
			(at -0.4 3.901 270)
			(layer "F.Fab")
			(effects
				(font
					(size 0.7 0.7)
					(thickness 0.15)
				)
				(justify left bottom)
			)
		)
		(fp_text user "${REFERENCE}"
			(at -0.4 2.7 270)
			(layer "F.Fab")
			(effects
				(font
					(size 0.7 0.7)
					(thickness 0.15)
				)
				(justify left bottom)
			)
		)
		(pad "1" thru_hole circle
			(at 0 0 270)
			(size 0.75 0.75)
			(drill 0.2)
			(layers "*.Cu" "*.Mask")
			(remove_unused_layers no)
			(net 134 "+3V3")
			(pinfunction "1")
			(pintype "passive")
		)
	)
	(footprint "antmicro-footprints:R_0402_1005Metric"
		(layer "F.Cu")
		(at 150.737 57.376 -90)
		(descr "Resistor SMD 0402")
		(tags "resistor SMD 0402")
		(property "Reference" "R25"
			(at 1.074 0.360999 90)
			(layer "F.SilkS")
			(effects
				(font
					(size 0.7 0.7)
					(thickness 0.15)
				)
				(justify right top)
			)
		)
		(property "Value" "R_1k_0402"
			(at -1.011843 1.772046 90)
			(layer "F.Fab")
			(effects
				(font
					(size 0.7 0.7)
					(thickness 0.15)
				)
				(justify right top)
			)
		)
		(property "Datasheet" "https://www.bourns.com/docs/product-datasheets/cr.pdf"
			(at 0 0 90)
			(layer "F.Fab")
			(hide yes)
			(effects
				(font
					(size 1.27 1.27)
					(thickness 0.15)
				)
			)
		)
		(property "Description" "SMD Chip Resistor, 1 kohm, ± 1%, 63 mW, 0402 [1005 Metric], Thick Film, General Purpose"
			(at 0 0 90)
			(layer "F.Fab")
			(hide yes)
			(effects
				(font
					(size 1.27 1.27)
					(thickness 0.15)
				)
			)
		)
		(property "MPN" "CR0402-FX-1001GLF"
			(at 0 0 270)
			(unlocked yes)
			(layer "F.Fab")
			(hide yes)
			(effects
				(font
					(size 1 1)
					(thickness 0.15)
				)
			)
		)
		(property "Manufacturer" "Bourns"
			(at 0 0 270)
			(unlocked yes)
			(layer "F.Fab")
			(hide yes)
			(effects
				(font
					(size 1 1)
					(thickness 0.15)
				)
			)
		)
		(property "License" "Apache-2.0"
			(at 0 0 270)
			(unlocked yes)
			(layer "F.Fab")
			(hide yes)
			(effects
				(font
					(size 1 1)
					(thickness 0.15)
				)
			)
		)
		(property "Author" "Antmicro"
			(at 0 0 270)
			(unlocked yes)
			(layer "F.Fab")
			(hide yes)
			(effects
				(font
					(size 1 1)
					(thickness 0.15)
				)
			)
		)
		(property "Val" "1k"
			(at 0 0 270)
			(unlocked yes)
			(layer "F.Fab")
			(hide yes)
			(effects
				(font
					(size 1 1)
					(thickness 0.15)
				)
			)
		)
		(property "Tolerance" "1%"
			(at 0 0 270)
			(unlocked yes)
			(layer "F.Fab")
			(hide yes)
			(effects
				(font
					(size 1 1)
					(thickness 0.15)
				)
			)
		)
		(sheetname "/USB-PD/")
		(sheetfile "usb-pd.kicad_sch")
		(attr smd)
		(fp_rect
			(start -0.925 -0.47)
			(end 0.925 0.47)
			(stroke
				(width 0.05)
				(type default)
			)
			(fill no)
			(layer "F.CrtYd")
		)
		(fp_rect
			(start -0.5 -0.25)
			(end 0.5 0.25)
			(stroke
				(width 0.15)
				(type solid)
			)
			(fill no)
			(layer "F.Fab")
		)
		(fp_text user "License: Apache-2.0"
			(at -0.949999 5.169 90)
			(layer "F.Fab")
			(effects
				(font
					(size 0.7 0.7)
					(thickness 0.15)
				)
				(justify right top)
			)
		)
		(fp_text user "${REFERENCE}"
			(at 0 0 90)
			(layer "F.Fab")
			(effects
				(font
					(size 0.7 0.7)
					(thickness 0.15)
				)
				(justify right top)
			)
		)
		(fp_text user "Author: Antmicro"
			(at -0.95 4.169 90)
			(layer "F.Fab")
			(effects
				(font
					(size 0.7 0.7)
					(thickness 0.15)
				)
				(justify right top)
			)
		)
		(pad "1" smd roundrect
			(at -0.48 0 270)
			(size 0.59 0.64)
			(layers "F.Cu" "F.Mask" "F.Paste")
			(roundrect_rratio 0.25)
			(net 138 "/USB-PD/ISNK_COARSE")
			(pintype "passive")
		)
		(pad "2" smd roundrect
			(at 0.48 0 270)
			(size 0.59 0.64)
			(layers "F.Cu" "F.Mask" "F.Paste")
			(roundrect_rratio 0.25)
			(net 117 "/USB-PD/VDDD_3V3")
			(pintype "passive")
		)
	)
)
